# BASEBOARD_FAB2 (Tioga Pass) — schematic netlist excerpt (pin names and nets, part order shuffled) for the footprints in the layout excerpt that follows; sources: Cadence DE-HDL packaged netlist, KiCad conversion of Wiwynn_Tioga_Pass_MB.brd

J8A1  CONN72_G97614002_A  CONN  pkg CP  page 173
  SIDEBANDA_7  = TP_FM_QAT_CBL_PRSNT0_R_N
  SIDEBANDA_0  = SGPIO_PCH_SATA_CLOCK_R
  GND(23)  = GND
  RXA1_DP  = SATA6G_P1_RX_C_DP
  RXA1_DN  = SATA6G_P1_RX_C_DN
  GND(22)  = GND
  RXA3_DP  = SATA6G_P3_RX_C_DP
  RXA3_DN  = SATA6G_P3_RX_C_DN
  GND(21)  = GND
  SIDEBANDA_3  = GND
  SIDEBANDA_1  = SGPIO_PCH_SATA_LOAD_R
  GND(20)  = GND
  RXA0_DP  = SATA6G_P0_RX_C_DP
  RXA0_DN  = SATA6G_P0_RX_C_DN
  GND(19)  = GND
  RXA2_DP  = SATA6G_P2_RX_C_DP
  RXA2_DN  = SATA6G_P2_RX_C_DN
  GND(18)  = GND
  SIDEBANDA_4  = SGPIO_PCH_SATA_DOUT0_R
  SIDEBANDA_2  = GND
  GND(17)  = GND
  TXA1_DP  = SATA6G_P1_TX_C_DP
  TXA1_DN  = SATA6G_P1_TX_C_DN
  GND(16)  = GND
  TXA3_DP  = SATA6G_P3_TX_C_DP
  TXA3_DN  = SATA6G_P3_TX_C_DN
  GND(15)  = GND
  SIDEBANDA_5  = PU_DATAIN1_SATA_0_R
  SIDEBANDA_6  = PD_SATA0_CONTROLLER_TYPE_R
  GND(14)  = GND
  TXA0_DP  = SATA6G_P0_TX_C_DP
  TXA0_DN  = SATA6G_P0_TX_C_DN
  GND(13)  = GND
  TXA2_DP  = SATA6G_P2_TX_C_DP
  TXA2_DN  = SATA6G_P2_TX_C_DN
  GND(12)  = GND
  SIDEBANDB_7  = TP_FM_QAT_CBL_PRSNT1_N_R
  SIDEBANDB_0  = TP_SGPIO_SATA_CLOCK1_R
  GND(11)  = GND
  RXB1_DP  = SATA6G_P5_RX_C_DP
  RXB1_DN  = SATA6G_P5_RX_C_DN
  GND(10)  = GND
  RXB3_DP  = SATA6G_P7_RX_C_DP
  RXB3_DN  = SATA6G_P7_RX_C_DN
  GND(9)  = GND
  SIDEBANDB_3  = GND
  SIDEBANDB_1  = TP_SGPIO_SATA_LOAD1_R
  GND(8)  = GND
  RXB0_DP  = SATA6G_P4_RX_C_DP
  RXB0_DN  = SATA6G_P4_RX_C_DN
  GND(7)  = GND
  RXB2_DP  = SATA6G_P6_RX_C_DP
  RXB2_DN  = SATA6G_P6_RX_C_DN
  GND(6)  = GND
  SIDEBANDB_4  = TP_SGPIO_SATA_DATA1_R
  SIDEBANDB_2  = GND
  GND(5)  = GND
  TXB1_DP  = SATA6G_P5_TX_C_DP
  TXB1_DN  = SATA6G_P5_TX_C_DN
  GND(4)  = GND
  TXB3_DP  = SATA6G_P7_TX_C_DP
  TXB3_DN  = SATA6G_P7_TX_C_DN
  GND(3)  = GND
  SIDEBANDB_5  = PU_DATAIN1_SATA_1_R
  SIDEBANDB_6  = PD_SATA1_CONTROLLER_TYPE_R
  GND(2)  = GND
  TXB0_DP  = SATA6G_P4_TX_C_DP
  TXB0_DN  = SATA6G_P4_TX_C_DN
  GND(1)  = GND
  TXB2_DP  = SATA6G_P6_TX_C_DP
  TXB2_DN  = SATA6G_P6_TX_C_DN
  GND(0)  = GND

(kicad_pcb
	(version 20260206)
	(generator "pcbnew")
	(generator_version "10.0")
	(general
		(thickness 1.6)
		(legacy_teardrops no)
	)
	(paper "A4")
	(title_block
		(title "Wiwynn_Tioga_Pass_MB.brd")
		(comment 1 "Tioga Pass / footprint 1251 of 4770 (J8A1), pads 63-77 of 77")
	)
	(layers
		(0 "F.Cu" signal "TOP")
		(4 "In1.Cu" signal "L2GND")
		(6 "In2.Cu" signal "L3")
		(8 "In3.Cu" signal "L4GND")
		(10 "In4.Cu" signal "L5")
		(12 "In5.Cu" signal "L6GND")
		(14 "In6.Cu" signal "L7VCC")
		(16 "In7.Cu" signal "L8VCC")
		(18 "In8.Cu" signal "L9GND")
		(20 "In9.Cu" signal "L10")
		(22 "In10.Cu" signal "L11GND")
		(24 "In11.Cu" signal "L12")
		(26 "In12.Cu" signal "L13GND")
		(2 "B.Cu" signal "BOTTOM")
		(9 "F.Adhes" user "F.Adhesive")
		(11 "B.Adhes" user "B.Adhesive")
		(13 "F.Paste" user "Package Geometry/Pastemask Top")
		(15 "B.Paste" user "Package Geometry/Pastemask Bottom")
		(5 "F.SilkS" user "Ref Des/Silkscreen Top")
		(7 "B.SilkS" user "Ref Des/Silkscreen Bottom")
		(1 "F.Mask" user "Board Geometry/Soldermask Top")
		(3 "B.Mask" user "Board Geometry/Soldermask Bottom")
		(17 "Dwgs.User" user "User.Drawings")
		(19 "Cmts.User" user "User.Comments")
		(21 "Eco1.User" user "User.Eco1")
		(23 "Eco2.User" user "User.Eco2")
		(25 "Edge.Cuts" user "Board Geometry/Outline")
		(27 "Margin" user)
		(31 "F.CrtYd" user "Package Geometry/Place Bound Top")
		(29 "B.CrtYd" user "Package Geometry/Place Bound Bottom")
		(35 "F.Fab" user "Ref Des/Assembly Top")
		(33 "B.Fab" user "Ref Des/Assembly Bottom")
	)
	(footprint ""
		(layer "F.Cu")
		(at 430.276 -154.94 -90)
		(property "Reference" "J8A1"
			(at 15.64767 10.287 0)
			(unlocked yes)
			(layer "B.SilkS")
			(effects
				(font
					(size 0.7874 0.5842)
					(thickness 0.1524)
				)
				(justify left mirror)
			)
		)
		(property "Value" ""
			(at 0 0 270)
			(layer "F.Fab")
			(effects
				(font
					(size 1.27 1.27)
				)
			)
		)
		(duplicate_pad_numbers_are_jumpers no)
		(pad "2C4" thru_hole circle
			(at 7.599934 14.249908 270)
			(size 0.7874 0.7874)
			(drill 0.381)
			(layers "*.Cu" "*.Mask")
			(remove_unused_layers no)
			(net "SATA6G_P5_TX_C_DP")
			(clearance 0.1143)
			(thermal_gap 0.1143)
		)
		(pad "2C5" thru_hole circle
			(at 6.199886 14.99997 270)
			(size 0.7874 0.7874)
			(drill 0.381)
			(layers "*.Cu" "*.Mask")
			(remove_unused_layers no)
			(net "SATA6G_P5_TX_C_DN")
			(clearance 0.1143)
			(thermal_gap 0.1143)
		)
		(pad "2C6" thru_hole circle
			(at 6.89991 15.750032 270)
			(size 0.7874 0.7874)
			(drill 0.381)
			(layers "*.Cu" "*.Mask")
			(remove_unused_layers no)
			(net "GND")
			(clearance 0.1143)
			(thermal_gap 0.1143)
		)
		(pad "2C7" thru_hole circle
			(at 7.599934 16.500094 270)
			(size 0.7874 0.7874)
			(drill 0.381)
			(layers "*.Cu" "*.Mask")
			(remove_unused_layers no)
			(net "SATA6G_P7_TX_C_DP")
			(clearance 0.1143)
			(thermal_gap 0.1143)
		)
		(pad "2C8" thru_hole circle
			(at 6.199886 17.249902 270)
			(size 0.7874 0.7874)
			(drill 0.381)
			(layers "*.Cu" "*.Mask")
			(remove_unused_layers no)
			(net "SATA6G_P7_TX_C_DN")
			(clearance 0.1143)
			(thermal_gap 0.1143)
		)
		(pad "2C9" thru_hole circle
			(at 6.89991 17.999964 270)
			(size 0.7874 0.7874)
			(drill 0.381)
			(layers "*.Cu" "*.Mask")
			(remove_unused_layers no)
			(net "GND")
			(clearance 0.1143)
			(thermal_gap 0.1143)
		)
		(pad "2D1" thru_hole circle
			(at 11.400028 11.999976 270)
			(size 0.7874 0.7874)
			(drill 0.381)
			(layers "*.Cu" "*.Mask")
			(remove_unused_layers no)
			(net "PU_DATAIN1_SATA_1_R")
			(clearance 0.1143)
			(thermal_gap 0.1143)
		)
		(pad "2D2" thru_hole circle
			(at 9.99998 12.750038 270)
			(size 0.7874 0.7874)
			(drill 0.381)
			(layers "*.Cu" "*.Mask")
			(remove_unused_layers no)
			(net "PD_SATA1_CONTROLLER_TYPE_R")
			(clearance 0.1143)
			(thermal_gap 0.1143)
		)
		(pad "2D3" thru_hole circle
			(at 10.700004 13.5001 270)
			(size 0.7874 0.7874)
			(drill 0.381)
			(layers "*.Cu" "*.Mask")
			(remove_unused_layers no)
			(net "GND")
			(clearance 0.1143)
			(thermal_gap 0.1143)
		)
		(pad "2D4" thru_hole circle
			(at 11.400028 14.249908 270)
			(size 0.7874 0.7874)
			(drill 0.381)
			(layers "*.Cu" "*.Mask")
			(remove_unused_layers no)
			(net "SATA6G_P4_TX_C_DP")
			(clearance 0.1143)
			(thermal_gap 0.1143)
		)
		(pad "2D5" thru_hole circle
			(at 9.99998 14.99997 270)
			(size 0.7874 0.7874)
			(drill 0.381)
			(layers "*.Cu" "*.Mask")
			(remove_unused_layers no)
			(net "SATA6G_P4_TX_C_DN")
			(clearance 0.1143)
			(thermal_gap 0.1143)
		)
		(pad "2D6" thru_hole circle
			(at 10.700004 15.750032 270)
			(size 0.7874 0.7874)
			(drill 0.381)
			(layers "*.Cu" "*.Mask")
			(remove_unused_layers no)
			(net "GND")
			(clearance 0.1143)
			(thermal_gap 0.1143)
		)
		(pad "2D7" thru_hole circle
			(at 11.400028 16.500094 270)
			(size 0.7874 0.7874)
			(drill 0.381)
			(layers "*.Cu" "*.Mask")
			(remove_unused_layers no)
			(net "SATA6G_P6_TX_C_DP")
			(clearance 0.1143)
			(thermal_gap 0.1143)
		)
		(pad "2D8" thru_hole circle
			(at 9.99998 17.249902 270)
			(size 0.7874 0.7874)
			(drill 0.381)
			(layers "*.Cu" "*.Mask")
			(remove_unused_layers no)
			(net "SATA6G_P6_TX_C_DN")
			(clearance 0.1143)
			(thermal_gap 0.1143)
		)
		(pad "2D9" thru_hole circle
			(at 10.700004 17.999964 270)
			(size 0.7874 0.7874)
			(drill 0.381)
			(layers "*.Cu" "*.Mask")
			(remove_unused_layers no)
			(net "GND")
			(clearance 0.1143)
			(thermal_gap 0.1143)
		)
	)
)
